(kicad_pcb
	(version 20241229)
	(generator "pcbnew")
	(generator_version "9.0")
	(general
		(thickness 1.599998)
		(legacy_teardrops no)
	)
	(paper "A4")
	(title_block
		(title "Artix - Datacenter Secure Control Module (DC-SCM)")
		(date "2024-11-06")
		(rev "1.1.3")
		(comment 9 "footprints 496-501 of 544")
	)
	(layers
		(0 "F.Cu" signal)
		(4 "In1.Cu" signal)
		(6 "In2.Cu" signal)
		(8 "In3.Cu" signal)
		(10 "In4.Cu" signal)
		(12 "In5.Cu" signal)
		(14 "In6.Cu" signal)
		(2 "B.Cu" signal)
		(9 "F.Adhes" user "F.Adhesive")
		(11 "B.Adhes" user "B.Adhesive")
		(13 "F.Paste" user)
		(15 "B.Paste" user)
		(5 "F.SilkS" user "F.Silkscreen")
		(7 "B.SilkS" user "B.Silkscreen")
		(1 "F.Mask" user)
		(3 "B.Mask" user)
		(17 "Dwgs.User" user "User.Drawings")
		(19 "Cmts.User" user "User.Comments")
		(21 "Eco1.User" user "User.Eco1")
		(23 "Eco2.User" user "User.Eco2")
		(25 "Edge.Cuts" user)
		(27 "Margin" user)
		(31 "F.CrtYd" user "F.Courtyard")
		(29 "B.CrtYd" user "B.Courtyard")
		(35 "F.Fab" user)
		(33 "B.Fab" user)
	)
	(footprint "antmicro-footprints:C_0402_1005Metric"
		(layer "B.Cu")
		(at 103.775 116.675 180)
		(descr "Capacitor SMD 0402")
		(tags "capacitor SMD 0402")
		(property "Reference" "C238"
			(at -2.025 1.475 0)
			(layer "B.SilkS")
			(effects
				(font
					(size 0.7 0.7)
					(thickness 0.15)
				)
				(justify left bottom mirror)
			)
		)
		(property "Value" "C_470n_0402"
			(at 0 -1.4 0)
			(layer "B.Fab")
			(effects
				(font
					(size 0.7 0.7)
					(thickness 0.15)
				)
				(justify left bottom mirror)
			)
		)
		(property "Datasheet" "https://product.tdk.com/en/search/capacitor/ceramic/mlcc/info?part_no=C1005X5R1E474M050BB"
			(at 0 0 180)
			(layer "F.Fab")
			(hide yes)
			(effects
				(font
					(size 1.27 1.27)
					(thickness 0.15)
				)
			)
		)
		(property "Description" "SMD Multilayer Ceramic Capacitor, 0.47 µF, 25 V, 0402 [1005 Metric], ± 20%, X5R, C"
			(at 0 0 180)
			(layer "F.Fab")
			(hide yes)
			(effects
				(font
					(size 1.27 1.27)
					(thickness 0.15)
				)
			)
		)
		(property "Author" "Antmicro"
			(at 207.55 233.35 0)
			(layer "B.Fab")
			(hide yes)
			(effects
				(font
					(size 1 1)
					(thickness 0.15)
				)
				(justify mirror)
			)
		)
		(property "Dielectric" ""
			(at 207.55 233.35 0)
			(layer "B.Fab")
			(hide yes)
			(effects
				(font
					(size 1 1)
					(thickness 0.15)
				)
				(justify mirror)
			)
		)
		(property "License" "Apache-2.0"
			(at 207.55 233.35 0)
			(layer "B.Fab")
			(hide yes)
			(effects
				(font
					(size 1 1)
					(thickness 0.15)
				)
				(justify mirror)
			)
		)
		(property "MPN" "C1005X5R1E474M050BB"
			(at 207.55 233.35 0)
			(layer "B.Fab")
			(hide yes)
			(effects
				(font
					(size 1 1)
					(thickness 0.15)
				)
				(justify mirror)
			)
		)
		(property "Manufacturer" "TDK"
			(at 207.55 233.35 0)
			(layer "B.Fab")
			(hide yes)
			(effects
				(font
					(size 1 1)
					(thickness 0.15)
				)
				(justify mirror)
			)
		)
		(property "Val" "470n"
			(at 207.55 233.35 0)
			(layer "B.Fab")
			(hide yes)
			(effects
				(font
					(size 1 1)
					(thickness 0.15)
				)
				(justify mirror)
			)
		)
		(property "Voltage" ""
			(at 207.55 233.35 0)
			(layer "B.Fab")
			(hide yes)
			(effects
				(font
					(size 1 1)
					(thickness 0.15)
				)
				(justify mirror)
			)
		)
		(property "DNP" ""
			(at 0 0 180)
			(unlocked yes)
			(layer "B.Fab")
			(hide yes)
			(effects
				(font
					(size 1 1)
					(thickness 0.15)
				)
				(justify mirror)
			)
		)
		(sheetname "/FPGA banks 13-16/")
		(sheetfile "fpga-banks-13-16.kicad_sch")
		(attr smd)
		(fp_rect
			(start -0.925 0.47)
			(end 0.925 -0.47)
			(stroke
				(width 0.05)
				(type default)
			)
			(fill no)
			(layer "B.CrtYd")
		)
		(fp_line
			(start 0.504 0.25)
			(end 0.504 -0.248)
			(stroke
				(width 0.15)
				(type solid)
			)
			(layer "B.Fab")
		)
		(fp_line
			(start 0.504 -0.248)
			(end -0.494 -0.248)
			(stroke
				(width 0.15)
				(type solid)
			)
			(layer "B.Fab")
		)
		(fp_line
			(start -0.494 0.25)
			(end 0.504 0.25)
			(stroke
				(width 0.15)
				(type solid)
			)
			(layer "B.Fab")
		)
		(fp_line
			(start -0.494 -0.248)
			(end -0.494 0.25)
			(stroke
				(width 0.15)
				(type solid)
			)
			(layer "B.Fab")
		)
		(pad "1" smd roundrect
			(at -0.48 0 180)
			(size 0.59 0.64)
			(layers "B.Cu" "B.Mask" "B.Paste")
			(roundrect_rratio 0.25)
			(net 1 "GND")
			(pintype "passive")
		)
		(pad "2" smd roundrect
			(at 0.48 0 180)
			(size 0.59 0.64)
			(layers "B.Cu" "B.Mask" "B.Paste")
			(roundrect_rratio 0.25)
			(net 2 "VCC3V3")
			(pintype "passive")
		)
	)
	(footprint "antmicro-footprints:R_0402_1005Metric"
		(layer "B.Cu")
		(at 104.175 141.875 90)
		(descr "Resistor SMD 0402")
		(tags "resistor SMD 0402")
		(property "Reference" "R180"
			(at 0.775 0.425 90)
			(layer "B.SilkS")
			(effects
				(font
					(size 0.7 0.7)
					(thickness 0.15)
				)
				(justify right bottom mirror)
			)
		)
		(property "Value" "R_51R_0402"
			(at 0 -1.4 90)
			(layer "B.Fab")
			(effects
				(font
					(size 0.7 0.7)
					(thickness 0.15)
				)
				(justify right bottom mirror)
			)
		)
		(property "Datasheet" "https://www.bourns.com/docs/product-datasheets/cr.pdf"
			(at 0 0 90)
			(layer "F.Fab")
			(hide yes)
			(effects
				(font
					(size 1.27 1.27)
					(thickness 0.15)
				)
			)
		)
		(property "Description" "SMD Chip Resistor, 51 ohm, ± 1%, 63 mW, 0402 [1005 Metric], Thick Film, General Purpose"
			(at 0 0 90)
			(layer "F.Fab")
			(hide yes)
			(effects
				(font
					(size 1.27 1.27)
					(thickness 0.15)
				)
			)
		)
		(property "Author" "Antmicro"
			(at 246.05 37.7 0)
			(layer "B.Fab")
			(hide yes)
			(effects
				(font
					(size 1 1)
					(thickness 0.15)
				)
				(justify mirror)
			)
		)
		(property "License" "Apache-2.0"
			(at 246.05 37.7 0)
			(layer "B.Fab")
			(hide yes)
			(effects
				(font
					(size 1 1)
					(thickness 0.15)
				)
				(justify mirror)
			)
		)
		(property "MPN" "CR0402-FX-51R0GLF"
			(at 246.05 37.7 0)
			(layer "B.Fab")
			(hide yes)
			(effects
				(font
					(size 1 1)
					(thickness 0.15)
				)
				(justify mirror)
			)
		)
		(property "Manufacturer" "Bourns"
			(at 246.05 37.7 0)
			(layer "B.Fab")
			(hide yes)
			(effects
				(font
					(size 1 1)
					(thickness 0.15)
				)
				(justify mirror)
			)
		)
		(property "Tolerance" "1%"
			(at 246.05 37.7 0)
			(layer "B.Fab")
			(hide yes)
			(effects
				(font
					(size 1 1)
					(thickness 0.15)
				)
				(justify mirror)
			)
		)
		(property "Val" "51R"
			(at 246.05 37.7 0)
			(layer "B.Fab")
			(hide yes)
			(effects
				(font
					(size 1 1)
					(thickness 0.15)
				)
				(justify mirror)
			)
		)
		(sheetname "/DDR3/")
		(sheetfile "ddr3.kicad_sch")
		(attr smd exclude_from_pos_files exclude_from_bom dnp)
		(fp_rect
			(start -0.925 0.47)
			(end 0.925 -0.47)
			(stroke
				(width 0.05)
				(type default)
			)
			(fill no)
			(layer "B.CrtYd")
		)
		(fp_rect
			(start -0.5 0.25)
			(end 0.5 -0.25)
			(stroke
				(width 0.15)
				(type solid)
			)
			(fill no)
			(layer "B.Fab")
		)
		(pad "1" smd roundrect
			(at -0.48 0 90)
			(size 0.59 0.64)
			(layers "B.Cu" "B.Mask" "B.Paste")
			(roundrect_rratio 0.25)
			(net 145 "DDR3_A8")
			(pintype "passive")
		)
		(pad "2" smd roundrect
			(at 0.48 0 90)
			(size 0.59 0.64)
			(layers "B.Cu" "B.Mask" "B.Paste")
			(roundrect_rratio 0.25)
			(net 143 "/DDR3/DDR3_VTT")
			(pintype "passive")
		)
	)
	(footprint "antmicro-footprints:C_0402_1005Metric"
		(layer "B.Cu")
		(at 90.275 112.475 -90)
		(descr "Capacitor SMD 0402")
		(tags "capacitor SMD 0402")
		(property "Reference" "C239"
			(at -1.375 0.475 90)
			(layer "B.SilkS")
			(effects
				(font
					(size 0.7 0.7)
					(thickness 0.15)
				)
				(justify left bottom mirror)
			)
		)
		(property "Value" "C_470n_0402"
			(at 0 -1.4 90)
			(layer "B.Fab")
			(effects
				(font
					(size 0.7 0.7)
					(thickness 0.15)
				)
				(justify left bottom mirror)
			)
		)
		(property "Datasheet" "https://product.tdk.com/en/search/capacitor/ceramic/mlcc/info?part_no=C1005X5R1E474M050BB"
			(at 0 0 270)
			(layer "F.Fab")
			(hide yes)
			(effects
				(font
					(size 1.27 1.27)
					(thickness 0.15)
				)
			)
		)
		(property "Description" "SMD Multilayer Ceramic Capacitor, 0.47 µF, 25 V, 0402 [1005 Metric], ± 20%, X5R, C"
			(at 0 0 270)
			(layer "F.Fab")
			(hide yes)
			(effects
				(font
					(size 1.27 1.27)
					(thickness 0.15)
				)
			)
		)
		(property "Author" "Antmicro"
			(at -22.2 202.75 0)
			(layer "B.Fab")
			(hide yes)
			(effects
				(font
					(size 1 1)
					(thickness 0.15)
				)
				(justify mirror)
			)
		)
		(property "Dielectric" ""
			(at -22.2 202.75 0)
			(layer "B.Fab")
			(hide yes)
			(effects
				(font
					(size 1 1)
					(thickness 0.15)
				)
				(justify mirror)
			)
		)
		(property "License" "Apache-2.0"
			(at -22.2 202.75 0)
			(layer "B.Fab")
			(hide yes)
			(effects
				(font
					(size 1 1)
					(thickness 0.15)
				)
				(justify mirror)
			)
		)
		(property "MPN" "C1005X5R1E474M050BB"
			(at -22.2 202.75 0)
			(layer "B.Fab")
			(hide yes)
			(effects
				(font
					(size 1 1)
					(thickness 0.15)
				)
				(justify mirror)
			)
		)
		(property "Manufacturer" "TDK"
			(at -22.2 202.75 0)
			(layer "B.Fab")
			(hide yes)
			(effects
				(font
					(size 1 1)
					(thickness 0.15)
				)
				(justify mirror)
			)
		)
		(property "Val" "470n"
			(at -22.2 202.75 0)
			(layer "B.Fab")
			(hide yes)
			(effects
				(font
					(size 1 1)
					(thickness 0.15)
				)
				(justify mirror)
			)
		)
		(property "Voltage" ""
			(at -22.2 202.75 0)
			(layer "B.Fab")
			(hide yes)
			(effects
				(font
					(size 1 1)
					(thickness 0.15)
				)
				(justify mirror)
			)
		)
		(sheetname "/FPGA banks 34-35 & CFG/")
		(sheetfile "fpga-banks-34-25-cfg.kicad_sch")
		(attr smd)
		(fp_rect
			(start -0.925 0.47)
			(end 0.925 -0.47)
			(stroke
				(width 0.05)
				(type default)
			)
			(fill no)
			(layer "B.CrtYd")
		)
		(fp_line
			(start -0.494 0.25)
			(end 0.504 0.25)
			(stroke
				(width 0.15)
				(type solid)
			)
			(layer "B.Fab")
		)
		(fp_line
			(start 0.504 0.25)
			(end 0.504 -0.248)
			(stroke
				(width 0.15)
				(type solid)
			)
			(layer "B.Fab")
		)
		(fp_line
			(start -0.494 -0.248)
			(end -0.494 0.25)
			(stroke
				(width 0.15)
				(type solid)
			)
			(layer "B.Fab")
		)
		(fp_line
			(start 0.504 -0.248)
			(end -0.494 -0.248)
			(stroke
				(width 0.15)
				(type solid)
			)
			(layer "B.Fab")
		)
		(pad "1" smd roundrect
			(at -0.48 0 270)
			(size 0.59 0.64)
			(layers "B.Cu" "B.Mask" "B.Paste")
			(roundrect_rratio 0.25)
			(net 1 "GND")
			(pintype "passive")
		)
		(pad "2" smd roundrect
			(at 0.48 0 270)
			(size 0.59 0.64)
			(layers "B.Cu" "B.Mask" "B.Paste")
			(roundrect_rratio 0.25)
			(net 2 "VCC3V3")
			(pintype "passive")
		)
	)
	(footprint "antmicro-footprints:C_0402_1005Metric"
		(layer "B.Cu")
		(at 90.825 117.325)
		(descr "Capacitor SMD 0402")
		(tags "capacitor SMD 0402")
		(property "Reference" "C240"
			(at -3.625 0.375 0)
			(layer "B.SilkS")
			(effects
				(font
					(size 0.7 0.7)
					(thickness 0.15)
				)
				(justify right bottom mirror)
			)
		)
		(property "Value" "C_470n_0402"
			(at 0 -1.4 0)
			(layer "B.Fab")
			(effects
				(font
					(size 0.7 0.7)
					(thickness 0.15)
				)
				(justify right bottom mirror)
			)
		)
		(property "Datasheet" "https://product.tdk.com/en/search/capacitor/ceramic/mlcc/info?part_no=C1005X5R1E474M050BB"
			(at 0 0 0)
			(layer "F.Fab")
			(hide yes)
			(effects
				(font
					(size 1.27 1.27)
					(thickness 0.15)
				)
			)
		)
		(property "Description" "SMD Multilayer Ceramic Capacitor, 0.47 µF, 25 V, 0402 [1005 Metric], ± 20%, X5R, C"
			(at 0 0 0)
			(layer "F.Fab")
			(hide yes)
			(effects
				(font
					(size 1.27 1.27)
					(thickness 0.15)
				)
			)
		)
		(property "Author" "Antmicro"
			(at 0 0 0)
			(layer "B.Fab")
			(hide yes)
			(effects
				(font
					(size 1 1)
					(thickness 0.15)
				)
				(justify mirror)
			)
		)
		(property "Dielectric" ""
			(at 0 0 0)
			(layer "B.Fab")
			(hide yes)
			(effects
				(font
					(size 1 1)
					(thickness 0.15)
				)
				(justify mirror)
			)
		)
		(property "License" "Apache-2.0"
			(at 0 0 0)
			(layer "B.Fab")
			(hide yes)
			(effects
				(font
					(size 1 1)
					(thickness 0.15)
				)
				(justify mirror)
			)
		)
		(property "MPN" "C1005X5R1E474M050BB"
			(at 0 0 0)
			(layer "B.Fab")
			(hide yes)
			(effects
				(font
					(size 1 1)
					(thickness 0.15)
				)
				(justify mirror)
			)
		)
		(property "Manufacturer" "TDK"
			(at 0 0 0)
			(layer "B.Fab")
			(hide yes)
			(effects
				(font
					(size 1 1)
					(thickness 0.15)
				)
				(justify mirror)
			)
		)
		(property "Val" "470n"
			(at 0 0 0)
			(layer "B.Fab")
			(hide yes)
			(effects
				(font
					(size 1 1)
					(thickness 0.15)
				)
				(justify mirror)
			)
		)
		(property "Voltage" ""
			(at 0 0 0)
			(layer "B.Fab")
			(hide yes)
			(effects
				(font
					(size 1 1)
					(thickness 0.15)
				)
				(justify mirror)
			)
		)
		(sheetname "/FPGA banks 13-16/")
		(sheetfile "fpga-banks-13-16.kicad_sch")
		(attr smd)
		(fp_rect
			(start -0.925 0.47)
			(end 0.925 -0.47)
			(stroke
				(width 0.05)
				(type default)
			)
			(fill no)
			(layer "B.CrtYd")
		)
		(fp_line
			(start -0.494 -0.248)
			(end -0.494 0.25)
			(stroke
				(width 0.15)
				(type solid)
			)
			(layer "B.Fab")
		)
		(fp_line
			(start -0.494 0.25)
			(end 0.504 0.25)
			(stroke
				(width 0.15)
				(type solid)
			)
			(layer "B.Fab")
		)
		(fp_line
			(start 0.504 -0.248)
			(end -0.494 -0.248)
			(stroke
				(width 0.15)
				(type solid)
			)
			(layer "B.Fab")
		)
		(fp_line
			(start 0.504 0.25)
			(end 0.504 -0.248)
			(stroke
				(width 0.15)
				(type solid)
			)
			(layer "B.Fab")
		)
		(pad "1" smd roundrect
			(at -0.48 0)
			(size 0.59 0.64)
			(layers "B.Cu" "B.Mask" "B.Paste")
			(roundrect_rratio 0.25)
			(net 1 "GND")
			(pintype "passive")
		)
		(pad "2" smd roundrect
			(at 0.48 0)
			(size 0.59 0.64)
			(layers "B.Cu" "B.Mask" "B.Paste")
			(roundrect_rratio 0.25)
			(net 2 "VCC3V3")
			(pintype "passive")
		)
	)
	(footprint "antmicro-footprints:R_0402_1005Metric"
		(layer "B.Cu")
		(at 91.975 158.875 180)
		(descr "Resistor SMD 0402")
		(tags "resistor SMD 0402")
		(property "Reference" "R88"
			(at 0.775 -0.325 0)
			(layer "B.SilkS")
			(effects
				(font
					(size 0.7 0.7)
					(thickness 0.15)
				)
				(justify left bottom mirror)
			)
		)
		(property "Value" "R_200R_0402"
			(at 0 -1.4 0)
			(layer "B.Fab")
			(effects
				(font
					(size 0.7 0.7)
					(thickness 0.15)
				)
				(justify left bottom mirror)
			)
		)
		(property "Datasheet" "https://www.bourns.com/docs/product-datasheets/cr.pdf"
			(at 0 0 180)
			(layer "F.Fab")
			(hide yes)
			(effects
				(font
					(size 1.27 1.27)
					(thickness 0.15)
				)
			)
		)
		(property "Description" "SMD Chip Resistor, 200 ohm, ± 1%, 62.5 mW, 0402 [1005 Metric], Thick Film, General Purpose"
			(at 0 0 180)
			(layer "F.Fab")
			(hide yes)
			(effects
				(font
					(size 1.27 1.27)
					(thickness 0.15)
				)
			)
		)
		(property "Author" "Antmicro"
			(at 183.95 317.75 0)
			(layer "B.Fab")
			(hide yes)
			(effects
				(font
					(size 1 1)
					(thickness 0.15)
				)
				(justify mirror)
			)
		)
		(property "License" "Apache-2.0"
			(at 183.95 317.75 0)
			(layer "B.Fab")
			(hide yes)
			(effects
				(font
					(size 1 1)
					(thickness 0.15)
				)
				(justify mirror)
			)
		)
		(property "MPN" "CR0402-FX-2000GLF"
			(at 183.95 317.75 0)
			(layer "B.Fab")
			(hide yes)
			(effects
				(font
					(size 1 1)
					(thickness 0.15)
				)
				(justify mirror)
			)
		)
		(property "Manufacturer" "Bourns"
			(at 183.95 317.75 0)
			(layer "B.Fab")
			(hide yes)
			(effects
				(font
					(size 1 1)
					(thickness 0.15)
				)
				(justify mirror)
			)
		)
		(property "Tolerance" "1%"
			(at 183.95 317.75 0)
			(layer "B.Fab")
			(hide yes)
			(effects
				(font
					(size 1 1)
					(thickness 0.15)
				)
				(justify mirror)
			)
		)
		(property "Val" "200R"
			(at 183.95 317.75 0)
			(layer "B.Fab")
			(hide yes)
			(effects
				(font
					(size 1 1)
					(thickness 0.15)
				)
				(justify mirror)
			)
		)
		(sheetname "/FPGA banks 34-35 & CFG/")
		(sheetfile "fpga-banks-34-25-cfg.kicad_sch")
		(attr smd)
		(fp_rect
			(start -0.925 0.47)
			(end 0.925 -0.47)
			(stroke
				(width 0.05)
				(type default)
			)
			(fill no)
			(layer "B.CrtYd")
		)
		(fp_rect
			(start -0.5 0.25)
			(end 0.5 -0.25)
			(stroke
				(width 0.15)
				(type solid)
			)
			(fill no)
			(layer "B.Fab")
		)
		(pad "1" smd roundrect
			(at -0.48 0 180)
			(size 0.59 0.64)
			(layers "B.Cu" "B.Mask" "B.Paste")
			(roundrect_rratio 0.25)
			(net 2 "VCC3V3")
			(pintype "passive")
		)
		(pad "2" smd roundrect
			(at 0.48 0 180)
			(size 0.59 0.64)
			(layers "B.Cu" "B.Mask" "B.Paste")
			(roundrect_rratio 0.25)
			(net 220 "DONE")
			(pintype "passive")
		)
	)
	(footprint "antmicro-footprints:C_0402_1005Metric"
		(layer "B.Cu")
		(at 91.175 122.675)
		(descr "Capacitor SMD 0402")
		(tags "capacitor SMD 0402")
		(property "Reference" "C193"
			(at -3.675 0.325 0)
			(layer "B.SilkS")
			(effects
				(font
					(size 0.7 0.7)
					(thickness 0.15)
				)
				(justify right bottom mirror)
			)
		)
		(property "Value" "C_100n_6V3_0402"
			(at 0 -1.4 0)
			(layer "B.Fab")
			(effects
				(font
					(size 0.7 0.7)
					(thickness 0.15)
				)
				(justify right bottom mirror)
			)
		)
		(property "Datasheet" "https://www.passivecomponent.com/wp-content/uploads/datasheet/WTC_MLCC_General_Purpose.pdf"
			(at 0 0 0)
			(layer "F.Fab")
			(hide yes)
			(effects
				(font
					(size 1.27 1.27)
					(thickness 0.15)
				)
			)
		)
		(property "Description" "SMT Multilayer Ceramic Capacitor, 0.1 µF, 6.3 V, 0402 [1005 Metric], ± 10%, X5R, Walsin MLCC"
			(at 0 0 0)
			(layer "F.Fab")
			(hide yes)
			(effects
				(font
					(size 1.27 1.27)
					(thickness 0.15)
				)
			)
		)
		(property "Author" "Antmicro"
			(at 0 0 0)
			(layer "B.Fab")
			(hide yes)
			(effects
				(font
					(size 1 1)
					(thickness 0.15)
				)
				(justify mirror)
			)
		)
		(property "Dielectric" ""
			(at 0 0 0)
			(layer "B.Fab")
			(hide yes)
			(effects
				(font
					(size 1 1)
					(thickness 0.15)
				)
				(justify mirror)
			)
		)
		(property "License" "Apache-2.0"
			(at 0 0 0)
			(layer "B.Fab")
			(hide yes)
			(effects
				(font
					(size 1 1)
					(thickness 0.15)
				)
				(justify mirror)
			)
		)
		(property "MPN" "0402X104K6R3CT"
			(at 0 0 0)
			(layer "B.Fab")
			(hide yes)
			(effects
				(font
					(size 1 1)
					(thickness 0.15)
				)
				(justify mirror)
			)
		)
		(property "Manufacturer" "Walsin"
			(at 0 0 0)
			(layer "B.Fab")
			(hide yes)
			(effects
				(font
					(size 1 1)
					(thickness 0.15)
				)
				(justify mirror)
			)
		)
		(property "Public" "False"
			(at 0 0 0)
			(layer "B.Fab")
			(hide yes)
			(effects
				(font
					(size 1 1)
					(thickness 0.15)
				)
				(justify mirror)
			)
		)
		(property "Val" "100n"
			(at 0 0 0)
			(layer "B.Fab")
			(hide yes)
			(effects
				(font
					(size 1 1)
					(thickness 0.15)
				)
				(justify mirror)
			)
		)
		(property "Voltage" ""
			(at 0 0 0)
			(layer "B.Fab")
			(hide yes)
			(effects
				(font
					(size 1 1)
					(thickness 0.15)
				)
				(justify mirror)
			)
		)
		(sheetname "/Interfaces/")
		(sheetfile "interfaces.kicad_sch")
		(attr smd)
		(fp_rect
			(start -0.925 0.47)
			(end 0.925 -0.47)
			(stroke
				(width 0.05)
				(type default)
			)
			(fill no)
			(layer "B.CrtYd")
		)
		(fp_line
			(start -0.494 -0.248)
			(end -0.494 0.25)
			(stroke
				(width 0.15)
				(type solid)
			)
			(layer "B.Fab")
		)
		(fp_line
			(start -0.494 0.25)
			(end 0.504 0.25)
			(stroke
				(width 0.15)
				(type solid)
			)
			(layer "B.Fab")
		)
		(fp_line
			(start 0.504 -0.248)
			(end -0.494 -0.248)
			(stroke
				(width 0.15)
				(type solid)
			)
			(layer "B.Fab")
		)
		(fp_line
			(start 0.504 0.25)
			(end 0.504 -0.248)
			(stroke
				(width 0.15)
				(type solid)
			)
			(layer "B.Fab")
		)
		(pad "1" smd roundrect
			(at -0.48 0)
			(size 0.59 0.64)
			(layers "B.Cu" "B.Mask" "B.Paste")
			(roundrect_rratio 0.25)
			(net 1 "GND")
			(pintype "passive")
		)
		(pad "2" smd roundrect
			(at 0.48 0)
			(size 0.59 0.64)
			(layers "B.Cu" "B.Mask" "B.Paste")
			(roundrect_rratio 0.25)
			(net 339 "VCC1V2")
			(pintype "passive")
		)
	)
)
